(kicad_pcb
	(version 20241229)
	(generator "pcbnew")
	(generator_version "9.0")
	(general
		(thickness 1.61)
		(legacy_teardrops no)
	)
	(paper "A3")
	(title_block
		(title "RDIMM DDR5 Tester")
		(date "2026-05-21")
		(rev "2.2.0")
		(company "Antmicro")
		(comment 9 "footprints 407-411 of 796")
	)
	(layers
		(0 "F.Cu" signal)
		(4 "In1.Cu" power)
		(6 "In2.Cu" mixed)
		(8 "In3.Cu" power)
		(10 "In4.Cu" mixed)
		(12 "In5.Cu" power)
		(14 "In6.Cu" mixed)
		(16 "In7.Cu" power)
		(18 "In8.Cu" power)
		(20 "In9.Cu" mixed)
		(22 "In10.Cu" power)
		(2 "B.Cu" signal)
		(9 "F.Adhes" user "F.Adhesive")
		(11 "B.Adhes" user "B.Adhesive")
		(13 "F.Paste" user)
		(15 "B.Paste" user)
		(5 "F.SilkS" user "F.Silkscreen")
		(7 "B.SilkS" user "B.Silkscreen")
		(1 "F.Mask" user)
		(3 "B.Mask" user)
		(17 "Dwgs.User" user "User.Drawings")
		(19 "Cmts.User" user "User.Comments")
		(21 "Eco1.User" user "User.Eco1")
		(23 "Eco2.User" user "User.Eco2")
		(25 "Edge.Cuts" user)
		(27 "Margin" user)
		(31 "F.CrtYd" user "F.Courtyard")
		(29 "B.CrtYd" user "B.Courtyard")
		(35 "F.Fab" user)
		(33 "B.Fab" user)
	)
	(footprint "antmicro-footprints:C_0402_1005Metric"
		(layer "B.Cu")
		(at 130.211328 138.082157 90)
		(descr "Capacitor SMD 0402")
		(tags "capacitor SMD 0402")
		(property "Reference" "C158"
			(at 1.176157 0.344672 90)
			(layer "B.SilkS")
			(effects
				(font
					(size 0.7 0.7)
					(thickness 0.15)
				)
				(justify right bottom mirror)
			)
		)
		(property "Value" "C_4u7_0402"
			(at -1.022927 -2.155213 90)
			(layer "B.Fab")
			(effects
				(font
					(size 0.7 0.7)
					(thickness 0.15)
				)
				(justify right bottom mirror)
			)
		)
		(property "Datasheet" "https://www.murata.com/products/productdetail?partno=GRM155R61A475MEAA%23"
			(at 0 0 90)
			(layer "F.Fab")
			(hide yes)
			(effects
				(font
					(size 1.27 1.27)
					(thickness 0.15)
				)
			)
		)
		(property "Manufacturer" "Murata"
			(at 0 0 90)
			(unlocked yes)
			(layer "B.Fab")
			(hide yes)
			(effects
				(font
					(size 1 1)
					(thickness 0.15)
				)
				(justify mirror)
			)
		)
		(property "MPN" "GRM155R61A475MEAAD"
			(at 0 0 90)
			(unlocked yes)
			(layer "B.Fab")
			(hide yes)
			(effects
				(font
					(size 1 1)
					(thickness 0.15)
				)
				(justify mirror)
			)
		)
		(property "Val" "4u7"
			(at 0 0 90)
			(unlocked yes)
			(layer "B.Fab")
			(hide yes)
			(effects
				(font
					(size 1 1)
					(thickness 0.15)
				)
				(justify mirror)
			)
		)
		(property "License" "Apache-2.0"
			(at 0 0 90)
			(unlocked yes)
			(layer "B.Fab")
			(hide yes)
			(effects
				(font
					(size 1 1)
					(thickness 0.15)
				)
				(justify mirror)
			)
		)
		(property "Author" "Antmicro"
			(at 0 0 90)
			(unlocked yes)
			(layer "B.Fab")
			(hide yes)
			(effects
				(font
					(size 1 1)
					(thickness 0.15)
				)
				(justify mirror)
			)
		)
		(property "Voltage" ""
			(at 0 0 90)
			(unlocked yes)
			(layer "B.Fab")
			(hide yes)
			(effects
				(font
					(size 1 1)
					(thickness 0.15)
				)
				(justify mirror)
			)
		)
		(property "Dielectric" ""
			(at 0 0 90)
			(unlocked yes)
			(layer "B.Fab")
			(hide yes)
			(effects
				(font
					(size 1 1)
					(thickness 0.15)
				)
				(justify mirror)
			)
		)
		(sheetname "/Ethernet/")
		(sheetfile "ethernet.kicad_sch")
		(attr smd)
		(fp_rect
			(start -0.925 0.47)
			(end 0.925 -0.47)
			(stroke
				(width 0.05)
				(type default)
			)
			(fill no)
			(layer "B.CrtYd")
		)
		(fp_line
			(start 0.504 -0.248)
			(end -0.494 -0.248)
			(stroke
				(width 0.15)
				(type solid)
			)
			(layer "B.Fab")
		)
		(fp_line
			(start -0.494 -0.248)
			(end -0.494 0.25)
			(stroke
				(width 0.15)
				(type solid)
			)
			(layer "B.Fab")
		)
		(fp_line
			(start 0.504 0.25)
			(end 0.504 -0.248)
			(stroke
				(width 0.15)
				(type solid)
			)
			(layer "B.Fab")
		)
		(fp_line
			(start -0.494 0.25)
			(end 0.504 0.25)
			(stroke
				(width 0.15)
				(type solid)
			)
			(layer "B.Fab")
		)
		(fp_text user "Author: Antmicro"
			(at -0.939 -3.399 270)
			(layer "B.Fab")
			(effects
				(font
					(size 0.7 0.7)
					(thickness 0.15)
				)
				(justify left bottom mirror)
			)
		)
		(fp_text user "${REFERENCE}"
			(at -0.939 -4.599 270)
			(layer "B.Fab")
			(effects
				(font
					(size 0.7 0.7)
					(thickness 0.15)
				)
				(justify left bottom mirror)
			)
		)
		(fp_text user "License: Apache-2.0"
			(at -0.939 -5.799 270)
			(layer "B.Fab")
			(effects
				(font
					(size 0.7 0.7)
					(thickness 0.15)
				)
				(justify left bottom mirror)
			)
		)
		(pad "1" smd roundrect
			(at -0.48 0 90)
			(size 0.59 0.64)
			(layers "B.Cu" "B.Mask" "B.Paste")
			(roundrect_rratio 0.25)
			(net 97 "/Ethernet/AVDDH")
			(pintype "passive")
		)
		(pad "2" smd roundrect
			(at 0.48 0 90)
			(size 0.59 0.64)
			(layers "B.Cu" "B.Mask" "B.Paste")
			(roundrect_rratio 0.25)
			(net 1 "GND")
			(pintype "passive")
		)
	)
	(footprint "antmicro-footprints:C_0402_1005Metric"
		(layer "B.Cu")
		(at 131.233171 146.453992 90)
		(descr "Capacitor SMD 0402")
		(tags "capacitor SMD 0402")
		(property "Reference" "C153"
			(at -3.914008 0.202829 90)
			(layer "B.SilkS")
			(effects
				(font
					(size 0.7 0.7)
					(thickness 0.15)
				)
				(justify right bottom mirror)
			)
		)
		(property "Value" "C_10n_0402"
			(at -1.022927 -2.155213 90)
			(layer "B.Fab")
			(effects
				(font
					(size 0.7 0.7)
					(thickness 0.15)
				)
				(justify right bottom mirror)
			)
		)
		(property "Datasheet" "https://www.murata.com/products/productdetail?partno=GRM155R71H103KA88%23"
			(at 0 0 90)
			(layer "F.Fab")
			(hide yes)
			(effects
				(font
					(size 1.27 1.27)
					(thickness 0.15)
				)
			)
		)
		(property "Manufacturer" "Murata"
			(at 0 0 90)
			(unlocked yes)
			(layer "B.Fab")
			(hide yes)
			(effects
				(font
					(size 1 1)
					(thickness 0.15)
				)
				(justify mirror)
			)
		)
		(property "MPN" "GRM155R71H103KA88D"
			(at 0 0 90)
			(unlocked yes)
			(layer "B.Fab")
			(hide yes)
			(effects
				(font
					(size 1 1)
					(thickness 0.15)
				)
				(justify mirror)
			)
		)
		(property "Val" "10n"
			(at 0 0 90)
			(unlocked yes)
			(layer "B.Fab")
			(hide yes)
			(effects
				(font
					(size 1 1)
					(thickness 0.15)
				)
				(justify mirror)
			)
		)
		(property "License" "Apache-2.0"
			(at 0 0 90)
			(unlocked yes)
			(layer "B.Fab")
			(hide yes)
			(effects
				(font
					(size 1 1)
					(thickness 0.15)
				)
				(justify mirror)
			)
		)
		(property "Author" "Antmicro"
			(at 0 0 90)
			(unlocked yes)
			(layer "B.Fab")
			(hide yes)
			(effects
				(font
					(size 1 1)
					(thickness 0.15)
				)
				(justify mirror)
			)
		)
		(property "Voltage" "50V"
			(at 0 0 90)
			(unlocked yes)
			(layer "B.Fab")
			(hide yes)
			(effects
				(font
					(size 1 1)
					(thickness 0.15)
				)
				(justify mirror)
			)
		)
		(property "Dielectric" "X7R"
			(at 0 0 90)
			(unlocked yes)
			(layer "B.Fab")
			(hide yes)
			(effects
				(font
					(size 1 1)
					(thickness 0.15)
				)
				(justify mirror)
			)
		)
		(sheetname "/Ethernet/")
		(sheetfile "ethernet.kicad_sch")
		(attr smd)
		(fp_rect
			(start -0.925 0.47)
			(end 0.925 -0.47)
			(stroke
				(width 0.05)
				(type default)
			)
			(fill no)
			(layer "B.CrtYd")
		)
		(fp_line
			(start 0.504 -0.248)
			(end -0.494 -0.248)
			(stroke
				(width 0.15)
				(type solid)
			)
			(layer "B.Fab")
		)
		(fp_line
			(start -0.494 -0.248)
			(end -0.494 0.25)
			(stroke
				(width 0.15)
				(type solid)
			)
			(layer "B.Fab")
		)
		(fp_line
			(start 0.504 0.25)
			(end 0.504 -0.248)
			(stroke
				(width 0.15)
				(type solid)
			)
			(layer "B.Fab")
		)
		(fp_line
			(start -0.494 0.25)
			(end 0.504 0.25)
			(stroke
				(width 0.15)
				(type solid)
			)
			(layer "B.Fab")
		)
		(fp_text user "License: Apache-2.0"
			(at -0.939 -5.799 270)
			(layer "B.Fab")
			(effects
				(font
					(size 0.7 0.7)
					(thickness 0.15)
				)
				(justify left bottom mirror)
			)
		)
		(fp_text user "${REFERENCE}"
			(at -0.939 -4.599 270)
			(layer "B.Fab")
			(effects
				(font
					(size 0.7 0.7)
					(thickness 0.15)
				)
				(justify left bottom mirror)
			)
		)
		(fp_text user "Author: Antmicro"
			(at -0.939 -3.399 270)
			(layer "B.Fab")
			(effects
				(font
					(size 0.7 0.7)
					(thickness 0.15)
				)
				(justify left bottom mirror)
			)
		)
		(pad "1" smd roundrect
			(at -0.48 0 90)
			(size 0.59 0.64)
			(layers "B.Cu" "B.Mask" "B.Paste")
			(roundrect_rratio 0.25)
			(net 150 "+1V2")
			(pintype "passive")
		)
		(pad "2" smd roundrect
			(at 0.48 0 90)
			(size 0.59 0.64)
			(layers "B.Cu" "B.Mask" "B.Paste")
			(roundrect_rratio 0.25)
			(net 1 "GND")
			(pintype "passive")
		)
	)
	(footprint "antmicro-footprints:C_0402_1005Metric"
		(layer "B.Cu")
		(at 131.36 141.95 90)
		(descr "Capacitor SMD 0402")
		(tags "capacitor SMD 0402")
		(property "Reference" "C156"
			(at -3.5 -0.3 90)
			(layer "B.SilkS")
			(effects
				(font
					(size 0.7 0.7)
					(thickness 0.15)
				)
				(justify right bottom mirror)
			)
		)
		(property "Value" "C_10n_0402"
			(at -1.022927 -2.155213 90)
			(layer "B.Fab")
			(effects
				(font
					(size 0.7 0.7)
					(thickness 0.15)
				)
				(justify right bottom mirror)
			)
		)
		(property "Datasheet" "https://www.murata.com/products/productdetail?partno=GRM155R71H103KA88%23"
			(at 0 0 90)
			(layer "F.Fab")
			(hide yes)
			(effects
				(font
					(size 1.27 1.27)
					(thickness 0.15)
				)
			)
		)
		(property "Manufacturer" "Murata"
			(at 0 0 90)
			(unlocked yes)
			(layer "B.Fab")
			(hide yes)
			(effects
				(font
					(size 1 1)
					(thickness 0.15)
				)
				(justify mirror)
			)
		)
		(property "MPN" "GRM155R71H103KA88D"
			(at 0 0 90)
			(unlocked yes)
			(layer "B.Fab")
			(hide yes)
			(effects
				(font
					(size 1 1)
					(thickness 0.15)
				)
				(justify mirror)
			)
		)
		(property "Val" "10n"
			(at 0 0 90)
			(unlocked yes)
			(layer "B.Fab")
			(hide yes)
			(effects
				(font
					(size 1 1)
					(thickness 0.15)
				)
				(justify mirror)
			)
		)
		(property "License" "Apache-2.0"
			(at 0 0 90)
			(unlocked yes)
			(layer "B.Fab")
			(hide yes)
			(effects
				(font
					(size 1 1)
					(thickness 0.15)
				)
				(justify mirror)
			)
		)
		(property "Author" "Antmicro"
			(at 0 0 90)
			(unlocked yes)
			(layer "B.Fab")
			(hide yes)
			(effects
				(font
					(size 1 1)
					(thickness 0.15)
				)
				(justify mirror)
			)
		)
		(property "Voltage" "50V"
			(at 0 0 90)
			(unlocked yes)
			(layer "B.Fab")
			(hide yes)
			(effects
				(font
					(size 1 1)
					(thickness 0.15)
				)
				(justify mirror)
			)
		)
		(property "Dielectric" "X7R"
			(at 0 0 90)
			(unlocked yes)
			(layer "B.Fab")
			(hide yes)
			(effects
				(font
					(size 1 1)
					(thickness 0.15)
				)
				(justify mirror)
			)
		)
		(sheetname "/Ethernet/")
		(sheetfile "ethernet.kicad_sch")
		(attr smd)
		(fp_rect
			(start -0.925 0.47)
			(end 0.925 -0.47)
			(stroke
				(width 0.05)
				(type default)
			)
			(fill no)
			(layer "B.CrtYd")
		)
		(fp_line
			(start 0.504 -0.248)
			(end -0.494 -0.248)
			(stroke
				(width 0.15)
				(type solid)
			)
			(layer "B.Fab")
		)
		(fp_line
			(start -0.494 -0.248)
			(end -0.494 0.25)
			(stroke
				(width 0.15)
				(type solid)
			)
			(layer "B.Fab")
		)
		(fp_line
			(start 0.504 0.25)
			(end 0.504 -0.248)
			(stroke
				(width 0.15)
				(type solid)
			)
			(layer "B.Fab")
		)
		(fp_line
			(start -0.494 0.25)
			(end 0.504 0.25)
			(stroke
				(width 0.15)
				(type solid)
			)
			(layer "B.Fab")
		)
		(fp_text user "License: Apache-2.0"
			(at -0.939 -5.799 270)
			(layer "B.Fab")
			(effects
				(font
					(size 0.7 0.7)
					(thickness 0.15)
				)
				(justify left bottom mirror)
			)
		)
		(fp_text user "${REFERENCE}"
			(at -0.939 -4.599 270)
			(layer "B.Fab")
			(effects
				(font
					(size 0.7 0.7)
					(thickness 0.15)
				)
				(justify left bottom mirror)
			)
		)
		(fp_text user "Author: Antmicro"
			(at -0.939 -3.399 270)
			(layer "B.Fab")
			(effects
				(font
					(size 0.7 0.7)
					(thickness 0.15)
				)
				(justify left bottom mirror)
			)
		)
		(pad "1" smd roundrect
			(at -0.48 0 90)
			(size 0.59 0.64)
			(layers "B.Cu" "B.Mask" "B.Paste")
			(roundrect_rratio 0.25)
			(net 150 "+1V2")
			(pintype "passive")
		)
		(pad "2" smd roundrect
			(at 0.48 0 90)
			(size 0.59 0.64)
			(layers "B.Cu" "B.Mask" "B.Paste")
			(roundrect_rratio 0.25)
			(net 1 "GND")
			(pintype "passive")
		)
	)
	(footprint "antmicro-footprints:FB_0603_1608Metric"
		(layer "B.Cu")
		(at 139.325 138.007851 180)
		(property "Reference" "FB5"
			(at -3.931 -0.168149 0)
			(layer "B.SilkS")
			(effects
				(font
					(size 0.7 0.7)
					(thickness 0.15)
				)
				(justify left bottom mirror)
			)
		)
		(property "Value" "FB_120Z_2A_Murata-BLM18PG_0603"
			(at 0 -1.5 0)
			(layer "B.Fab")
			(effects
				(font
					(size 0.7 0.7)
					(thickness 0.15)
				)
				(justify left bottom mirror)
			)
		)
		(property "Datasheet" "https://www.murata.com/en-us/products/productdata/8796738650142/ENFA0003.pdf"
			(at 0 0 180)
			(layer "F.Fab")
			(hide yes)
			(effects
				(font
					(size 1.27 1.27)
					(thickness 0.15)
				)
			)
		)
		(property "Val" "120Z/2A"
			(at 0 0 180)
			(unlocked yes)
			(layer "B.Fab")
			(hide yes)
			(effects
				(font
					(size 1 1)
					(thickness 0.15)
				)
				(justify mirror)
			)
		)
		(property "MPN" "BLM18PG121SN1D"
			(at 0 0 180)
			(unlocked yes)
			(layer "B.Fab")
			(hide yes)
			(effects
				(font
					(size 1 1)
					(thickness 0.15)
				)
				(justify mirror)
			)
		)
		(property "Manufacturer" "Murata"
			(at 0 0 180)
			(unlocked yes)
			(layer "B.Fab")
			(hide yes)
			(effects
				(font
					(size 1 1)
					(thickness 0.15)
				)
				(justify mirror)
			)
		)
		(property "Author" "Antmicro"
			(at 0 0 180)
			(unlocked yes)
			(layer "B.Fab")
			(hide yes)
			(effects
				(font
					(size 1 1)
					(thickness 0.15)
				)
				(justify mirror)
			)
		)
		(property "License" "Apache-2.0"
			(at 0 0 180)
			(unlocked yes)
			(layer "B.Fab")
			(hide yes)
			(effects
				(font
					(size 1 1)
					(thickness 0.15)
				)
				(justify mirror)
			)
		)
		(sheetname "/Ethernet/")
		(sheetfile "ethernet.kicad_sch")
		(attr smd)
		(fp_line
			(start -0.15 0.4)
			(end 0.15 0.4)
			(stroke
				(width 0.15)
				(type solid)
			)
			(layer "B.SilkS")
		)
		(fp_line
			(start -0.15 -0.4)
			(end 0.15 -0.4)
			(stroke
				(width 0.15)
				(type solid)
			)
			(layer "B.SilkS")
		)
		(fp_rect
			(start -1.25 0.65)
			(end 1.25 -0.65)
			(stroke
				(width 0.05)
				(type solid)
			)
			(fill no)
			(layer "B.CrtYd")
		)
		(fp_line
			(start 0.8 0.408)
			(end 0.8 -0.406)
			(stroke
				(width 0.15)
				(type solid)
			)
			(layer "B.Fab")
		)
		(fp_line
			(start 0.8 0.408)
			(end -0.803 0.408)
			(stroke
				(width 0.15)
				(type solid)
			)
			(layer "B.Fab")
		)
		(fp_line
			(start 0.8 -0.406)
			(end -0.803 -0.406)
			(stroke
				(width 0.15)
				(type solid)
			)
			(layer "B.Fab")
		)
		(fp_line
			(start -0.803 -0.406)
			(end -0.803 0.408)
			(stroke
				(width 0.15)
				(type solid)
			)
			(layer "B.Fab")
		)
		(fp_text user "Author: Antmicro"
			(at -1.653 -3.162 0)
			(layer "B.Fab")
			(effects
				(font
					(size 0.7 0.7)
					(thickness 0.15)
				)
				(justify left bottom mirror)
			)
		)
		(fp_text user "License: Apache-2.0"
			(at -1.653 -5.9 0)
			(layer "B.Fab")
			(effects
				(font
					(size 0.7 0.7)
					(thickness 0.15)
				)
				(justify left bottom mirror)
			)
		)
		(fp_text user "${REFERENCE}"
			(at -1.653 -4.6 0)
			(layer "B.Fab")
			(effects
				(font
					(size 0.7 0.7)
					(thickness 0.15)
				)
				(justify left bottom mirror)
			)
		)
		(pad "1" smd roundrect
			(at -0.7 0 180)
			(size 0.8 1)
			(layers "B.Cu" "B.Mask" "B.Paste")
			(roundrect_rratio 0.2)
			(net 151 "+3V3")
			(pintype "passive")
		)
		(pad "2" smd roundrect
			(at 0.7 0 180)
			(size 0.8 1)
			(layers "B.Cu" "B.Mask" "B.Paste")
			(roundrect_rratio 0.2)
			(net 97 "/Ethernet/AVDDH")
			(pintype "passive")
		)
	)
	(footprint "antmicro-footprints:FB_0603_1608Metric"
		(layer "B.Cu")
		(at 134.211328 141.007157)
		(property "Reference" "FB4"
			(at 1.424672 0.470843 0)
			(layer "B.SilkS")
			(effects
				(font
					(size 0.7 0.7)
					(thickness 0.15)
				)
				(justify right bottom mirror)
			)
		)
		(property "Value" "FB_120Z_2A_Murata-BLM18PG_0603"
			(at 0 -1.5 0)
			(layer "B.Fab")
			(effects
				(font
					(size 0.7 0.7)
					(thickness 0.15)
				)
				(justify right bottom mirror)
			)
		)
		(property "Datasheet" "https://www.murata.com/en-us/products/productdata/8796738650142/ENFA0003.pdf"
			(at 0 0 0)
			(layer "F.Fab")
			(hide yes)
			(effects
				(font
					(size 1.27 1.27)
					(thickness 0.15)
				)
			)
		)
		(property "Val" "120Z/2A"
			(at 0 0 0)
			(unlocked yes)
			(layer "B.Fab")
			(hide yes)
			(effects
				(font
					(size 1 1)
					(thickness 0.15)
				)
				(justify mirror)
			)
		)
		(property "MPN" "BLM18PG121SN1D"
			(at 0 0 0)
			(unlocked yes)
			(layer "B.Fab")
			(hide yes)
			(effects
				(font
					(size 1 1)
					(thickness 0.15)
				)
				(justify mirror)
			)
		)
		(property "Manufacturer" "Murata"
			(at 0 0 0)
			(unlocked yes)
			(layer "B.Fab")
			(hide yes)
			(effects
				(font
					(size 1 1)
					(thickness 0.15)
				)
				(justify mirror)
			)
		)
		(property "Author" "Antmicro"
			(at 0 0 0)
			(unlocked yes)
			(layer "B.Fab")
			(hide yes)
			(effects
				(font
					(size 1 1)
					(thickness 0.15)
				)
				(justify mirror)
			)
		)
		(property "License" "Apache-2.0"
			(at 0 0 0)
			(unlocked yes)
			(layer "B.Fab")
			(hide yes)
			(effects
				(font
					(size 1 1)
					(thickness 0.15)
				)
				(justify mirror)
			)
		)
		(sheetname "/Ethernet/")
		(sheetfile "ethernet.kicad_sch")
		(attr smd)
		(fp_line
			(start -0.15 -0.4)
			(end 0.15 -0.4)
			(stroke
				(width 0.15)
				(type solid)
			)
			(layer "B.SilkS")
		)
		(fp_line
			(start -0.15 0.4)
			(end 0.15 0.4)
			(stroke
				(width 0.15)
				(type solid)
			)
			(layer "B.SilkS")
		)
		(fp_rect
			(start -1.25 0.65)
			(end 1.25 -0.65)
			(stroke
				(width 0.05)
				(type solid)
			)
			(fill no)
			(layer "B.CrtYd")
		)
		(fp_line
			(start -0.803 -0.406)
			(end -0.803 0.408)
			(stroke
				(width 0.15)
				(type solid)
			)
			(layer "B.Fab")
		)
		(fp_line
			(start 0.8 -0.406)
			(end -0.803 -0.406)
			(stroke
				(width 0.15)
				(type solid)
			)
			(layer "B.Fab")
		)
		(fp_line
			(start 0.8 0.408)
			(end -0.803 0.408)
			(stroke
				(width 0.15)
				(type solid)
			)
			(layer "B.Fab")
		)
		(fp_line
			(start 0.8 0.408)
			(end 0.8 -0.406)
			(stroke
				(width 0.15)
				(type solid)
			)
			(layer "B.Fab")
		)
		(fp_text user "Author: Antmicro"
			(at -1.653 -3.162 180)
			(layer "B.Fab")
			(effects
				(font
					(size 0.7 0.7)
					(thickness 0.15)
				)
				(justify left bottom mirror)
			)
		)
		(fp_text user "License: Apache-2.0"
			(at -1.653 -5.9 180)
			(layer "B.Fab")
			(effects
				(font
					(size 0.7 0.7)
					(thickness 0.15)
				)
				(justify left bottom mirror)
			)
		)
		(fp_text user "${REFERENCE}"
			(at -1.653 -4.6 180)
			(layer "B.Fab")
			(effects
				(font
					(size 0.7 0.7)
					(thickness 0.15)
				)
				(justify left bottom mirror)
			)
		)
		(pad "1" smd roundrect
			(at -0.7 0)
			(size 0.8 1)
			(layers "B.Cu" "B.Mask" "B.Paste")
			(roundrect_rratio 0.2)
			(net 150 "+1V2")
			(pintype "passive")
		)
		(pad "2" smd roundrect
			(at 0.7 0)
			(size 0.8 1)
			(layers "B.Cu" "B.Mask" "B.Paste")
			(roundrect_rratio 0.2)
			(net 95 "/Ethernet/AVDDL")
			(pintype "passive")
		)
	)
)
